# BASEBOARD_FAB2 (Tioga Pass) — schematic netlist excerpt (pin names and nets, part order shuffled) for the footprints in the layout excerpt that follows; sources: Cadence DE-HDL packaged netlist, KiCad conversion of Wiwynn_Tioga_Pass_MB.brd

R1L29  RES  33.2 1% CHIP  pkg 0402  page 111 : A = FM_DEBUG_RST_BTN_R1_N ; B = FM_DEBUG_RST_BTN_N
R8W5  RES  20.0 1% CHIP  pkg 0402  page 138 : A = SMB_HOST_STBY_LVC3_SCL ; B = SMB_HOST_STBY_LVC3_SCL_R5
C5L11  CAP_A  47UF 4V 20% X5R  pkg 0603V  page 220 : A = PVDDQ_DEF ; B = GND

(kicad_pcb
	(version 20260206)
	(generator "pcbnew")
	(generator_version "10.0")
	(general
		(thickness 1.6)
		(legacy_teardrops no)
	)
	(paper "A4")
	(title_block
		(title "Wiwynn_Tioga_Pass_MB.brd")
		(comment 1 "Tioga Pass / footprints 3567-3569 of 4770")
	)
	(layers
		(0 "F.Cu" signal "TOP")
		(4 "In1.Cu" signal "L2GND")
		(6 "In2.Cu" signal "L3")
		(8 "In3.Cu" signal "L4GND")
		(10 "In4.Cu" signal "L5")
		(12 "In5.Cu" signal "L6GND")
		(14 "In6.Cu" signal "L7VCC")
		(16 "In7.Cu" signal "L8VCC")
		(18 "In8.Cu" signal "L9GND")
		(20 "In9.Cu" signal "L10")
		(22 "In10.Cu" signal "L11GND")
		(24 "In11.Cu" signal "L12")
		(26 "In12.Cu" signal "L13GND")
		(2 "B.Cu" signal "BOTTOM")
		(9 "F.Adhes" user "F.Adhesive")
		(11 "B.Adhes" user "B.Adhesive")
		(13 "F.Paste" user "Package Geometry/Pastemask Top")
		(15 "B.Paste" user "Package Geometry/Pastemask Bottom")
		(5 "F.SilkS" user "Ref Des/Silkscreen Top")
		(7 "B.SilkS" user "Ref Des/Silkscreen Bottom")
		(1 "F.Mask" user "Board Geometry/Soldermask Top")
		(3 "B.Mask" user "Board Geometry/Soldermask Bottom")
		(17 "Dwgs.User" user "User.Drawings")
		(19 "Cmts.User" user "User.Comments")
		(21 "Eco1.User" user "User.Eco1")
		(23 "Eco2.User" user "User.Eco2")
		(25 "Edge.Cuts" user "Board Geometry/Outline")
		(27 "Margin" user)
		(31 "F.CrtYd" user "Package Geometry/Place Bound Top")
		(29 "B.CrtYd" user "Package Geometry/Place Bound Bottom")
		(35 "F.Fab" user "Ref Des/Assembly Top")
		(33 "B.Fab" user "Ref Des/Assembly Bottom")
	)
	(footprint ""
		(layer "B.Cu")
		(at 456.7936 -142.9004)
		(property "Reference" "R1L29"
			(at 0 0 0)
			(layer "B.SilkS")
			(hide yes)
			(effects
				(font
					(size 1.27 1.27)
				)
				(justify mirror)
			)
		)
		(property "Value" ""
			(at 0 0 0)
			(layer "B.Fab")
			(effects
				(font
					(size 1.27 1.27)
				)
				(justify mirror)
			)
		)
		(duplicate_pad_numbers_are_jumpers no)
		(fp_poly
			(pts
				(xy 0.2794 -0.1016) (xy -0.2794 -0.1016) (xy -0.2794 0.9906) (xy 0.2794 0.9906)
			)
			(stroke
				(width 0)
				(type default)
			)
			(fill no)
			(layer "B.CrtYd")
		)
		(fp_line
			(start -0.2794 -0.1016)
			(end 0.2794 -0.1016)
			(stroke
				(width 0.1)
				(type default)
			)
			(layer "B.Fab")
		)
		(fp_line
			(start -0.2794 0.9906)
			(end -0.2794 -0.1016)
			(stroke
				(width 0.1)
				(type default)
			)
			(layer "B.Fab")
		)
		(fp_line
			(start 0.2794 -0.1016)
			(end 0.2794 0.9906)
			(stroke
				(width 0.1)
				(type default)
			)
			(layer "B.Fab")
		)
		(fp_line
			(start 0.2794 0.9906)
			(end -0.2794 0.9906)
			(stroke
				(width 0.1)
				(type default)
			)
			(layer "B.Fab")
		)
		(pad "1" smd rect
			(at 0 0 180)
			(size 0.508 0.508)
			(layers "B.Cu" "B.Mask" "B.Paste")
			(net "FM_DEBUG_RST_BTN_R1_N")
		)
		(pad "2" smd rect
			(at 0 0.889 180)
			(size 0.508 0.508)
			(layers "B.Cu" "B.Mask" "B.Paste")
			(net "FM_DEBUG_RST_BTN_N")
		)
		(zone
			(layer "B.Cu")
			(hatch none 0.5)
			(connect_pads
				(clearance 0)
			)
			(min_thickness 0.25)
			(keepout
				(tracks allowed)
				(vias not_allowed)
				(pads allowed)
				(copperpour not_allowed)
				(footprints allowed)
			)
			(placement
				(enabled no)
				(sheetname "")
			)
			(fill
				(thermal_gap 0.5)
				(thermal_bridge_width 0.5)
				(island_removal_mode 0)
			)
			(polygon
				(pts
					(xy 457.0476 -142.6464) (xy 456.5396 -142.6464) (xy 456.5396 -142.2654) (xy 457.0476 -142.2654)
				)
			)
		)
		(zone
			(layer "B.Cu")
			(hatch none 0.5)
			(connect_pads
				(clearance 0)
			)
			(min_thickness 0.25)
			(keepout
				(tracks not_allowed)
				(vias allowed)
				(pads allowed)
				(copperpour not_allowed)
				(footprints allowed)
			)
			(placement
				(enabled no)
				(sheetname "")
			)
			(fill
				(thermal_gap 0.5)
				(thermal_bridge_width 0.5)
				(island_removal_mode 0)
			)
			(polygon
				(pts
					(xy 457.0476 -142.2654) (xy 456.5396 -142.2654) (xy 456.5396 -142.6464) (xy 457.0476 -142.6464)
				)
			)
		)
	)
	(footprint ""
		(layer "B.Cu")
		(at 252.1585 -145.0086 -90)
		(property "Reference" "C5L11"
			(at -1.848866 0.752348 270)
			(unlocked yes)
			(layer "B.SilkS")
			(effects
				(font
					(size 1.27 0.9652)
					(thickness 0.1524)
				)
				(justify mirror)
			)
		)
		(property "Value" ""
			(at 0 0 90)
			(layer "B.Fab")
			(effects
				(font
					(size 1.27 1.27)
				)
				(justify mirror)
			)
		)
		(duplicate_pad_numbers_are_jumpers no)
		(fp_rect
			(start 0.500126 1.598422)
			(end -0.500126 -0.201422)
			(stroke
				(width 0)
				(type default)
			)
			(fill no)
			(layer "B.CrtYd")
		)
		(fp_line
			(start -0.500126 1.598422)
			(end 0.500126 1.598422)
			(stroke
				(width 0.1)
				(type default)
			)
			(layer "B.Fab")
		)
		(fp_line
			(start 0.500126 1.598422)
			(end 0.500126 -0.201422)
			(stroke
				(width 0.1)
				(type default)
			)
			(layer "B.Fab")
		)
		(fp_line
			(start -0.500126 -0.201422)
			(end -0.500126 1.598422)
			(stroke
				(width 0.1)
				(type default)
			)
			(layer "B.Fab")
		)
		(fp_line
			(start 0.500126 -0.201422)
			(end -0.500126 -0.201422)
			(stroke
				(width 0.1)
				(type default)
			)
			(layer "B.Fab")
		)
		(pad "1" smd rect
			(at 0 0 180)
			(size 0.889 0.9906)
			(layers "B.Cu" "B.Mask" "B.Paste")
			(net "PVDDQ_DEF")
		)
		(pad "2" smd rect
			(at 0 1.397 180)
			(size 0.889 0.9906)
			(layers "B.Cu" "B.Mask" "B.Paste")
			(net "GND")
		)
		(zone
			(layer "B.Cu")
			(hatch none 0.5)
			(connect_pads
				(clearance 0)
			)
			(min_thickness 0.25)
			(keepout
				(tracks allowed)
				(vias not_allowed)
				(pads allowed)
				(copperpour not_allowed)
				(footprints allowed)
			)
			(placement
				(enabled no)
				(sheetname "")
			)
			(fill
				(thermal_gap 0.5)
				(thermal_bridge_width 0.5)
				(island_removal_mode 0)
			)
			(polygon
				(pts
					(xy 251.206 -144.5133) (xy 251.714 -144.5133) (xy 251.714 -145.5039) (xy 251.206 -145.5039)
				)
			)
		)
		(zone
			(layer "B.Cu")
			(hatch none 0.5)
			(connect_pads
				(clearance 0)
			)
			(min_thickness 0.25)
			(keepout
				(tracks not_allowed)
				(vias allowed)
				(pads allowed)
				(copperpour not_allowed)
				(footprints allowed)
			)
			(placement
				(enabled no)
				(sheetname "")
			)
			(fill
				(thermal_gap 0.5)
				(thermal_bridge_width 0.5)
				(island_removal_mode 0)
			)
			(polygon
				(pts
					(xy 251.206 -144.5133) (xy 251.714 -144.5133) (xy 251.714 -145.5039) (xy 251.206 -145.5039)
				)
			)
		)
	)
	(footprint ""
		(layer "B.Cu")
		(at 447.157094 -23.642574 -90)
		(property "Reference" "R8W5"
			(at 0.8382 -0.67818 270)
			(unlocked yes)
			(layer "B.SilkS")
			(effects
				(font
					(size 0.4064 0.254)
					(thickness 0.1524)
				)
				(justify left mirror)
			)
		)
		(property "Value" ""
			(at 0 0 90)
			(layer "B.Fab")
			(effects
				(font
					(size 1.27 1.27)
				)
				(justify mirror)
			)
		)
		(duplicate_pad_numbers_are_jumpers no)
		(fp_poly
			(pts
				(xy 0.2794 -0.1016) (xy -0.2794 -0.1016) (xy -0.2794 0.9906) (xy 0.2794 0.9906)
			)
			(stroke
				(width 0)
				(type default)
			)
			(fill no)
			(layer "B.CrtYd")
		)
		(fp_line
			(start -0.2794 0.9906)
			(end -0.2794 -0.1016)
			(stroke
				(width 0.1)
				(type default)
			)
			(layer "B.Fab")
		)
		(fp_line
			(start 0.2794 0.9906)
			(end -0.2794 0.9906)
			(stroke
				(width 0.1)
				(type default)
			)
			(layer "B.Fab")
		)
		(fp_line
			(start -0.2794 -0.1016)
			(end 0.2794 -0.1016)
			(stroke
				(width 0.1)
				(type default)
			)
			(layer "B.Fab")
		)
		(fp_line
			(start 0.2794 -0.1016)
			(end 0.2794 0.9906)
			(stroke
				(width 0.1)
				(type default)
			)
			(layer "B.Fab")
		)
		(pad "1" smd rect
			(at 0 0 90)
			(size 0.508 0.508)
			(layers "B.Cu" "B.Mask" "B.Paste")
			(net "SMB_HOST_STBY_LVC3_SCL")
		)
		(pad "2" smd rect
			(at 0 0.889 90)
			(size 0.508 0.508)
			(layers "B.Cu" "B.Mask" "B.Paste")
			(net "SMB_HOST_STBY_LVC3_SCL_R5")
		)
		(zone
			(layer "B.Cu")
			(hatch none 0.5)
			(connect_pads
				(clearance 0)
			)
			(min_thickness 0.25)
			(keepout
				(tracks not_allowed)
				(vias allowed)
				(pads allowed)
				(copperpour not_allowed)
				(footprints allowed)
			)
			(placement
				(enabled no)
				(sheetname "")
			)
			(fill
				(thermal_gap 0.5)
				(thermal_bridge_width 0.5)
				(island_removal_mode 0)
			)
			(polygon
				(pts
					(xy 446.522094 -23.388574) (xy 446.522094 -23.896574) (xy 446.903094 -23.896574) (xy 446.903094 -23.388574)
				)
			)
		)
		(zone
			(layer "B.Cu")
			(hatch none 0.5)
			(connect_pads
				(clearance 0)
			)
			(min_thickness 0.25)
			(keepout
				(tracks allowed)
				(vias not_allowed)
				(pads allowed)
				(copperpour not_allowed)
				(footprints allowed)
			)
			(placement
				(enabled no)
				(sheetname "")
			)
			(fill
				(thermal_gap 0.5)
				(thermal_bridge_width 0.5)
				(island_removal_mode 0)
			)
			(polygon
				(pts
					(xy 446.903094 -23.388574) (xy 446.903094 -23.896574) (xy 446.522094 -23.896574) (xy 446.522094 -23.388574)
				)
			)
		)
	)
)
